# BASEBOARD_FAB2 (Tioga Pass) — schematic netlist excerpt (pin names and nets, part order shuffled) for the footprints in the layout excerpt that follows; sources: Cadence DE-HDL packaged netlist, KiCad conversion of Wiwynn_Tioga_Pass_MB.brd

R2U9  RES  20.0 1% CHIP  pkg 0402  page 138 : A = SMB_LAN_STBY_LVC3_SDA_R1 ; B = SMB_LAN_STBY_LVC3_SDA
R8B31  RES  4.75K 1% CHIP  pkg 0402  page 133 : A = P3V3_STBY ; B = FM_THROTTLE_N
C4F12  CAP  3300PF 50V 10% EMPTY  pkg 0402LF  page 233 : A = VR_PVPP_GHJ_PHASE ; B = VR_PVPP_GHJ_SNUB

(kicad_pcb
	(version 20260206)
	(generator "pcbnew")
	(generator_version "10.0")
	(general
		(thickness 1.6)
		(legacy_teardrops no)
	)
	(paper "A4")
	(title_block
		(title "Wiwynn_Tioga_Pass_MB.brd")
		(comment 1 "Tioga Pass / footprints 1413-1415 of 4770")
	)
	(layers
		(0 "F.Cu" signal "TOP")
		(4 "In1.Cu" signal "L2GND")
		(6 "In2.Cu" signal "L3")
		(8 "In3.Cu" signal "L4GND")
		(10 "In4.Cu" signal "L5")
		(12 "In5.Cu" signal "L6GND")
		(14 "In6.Cu" signal "L7VCC")
		(16 "In7.Cu" signal "L8VCC")
		(18 "In8.Cu" signal "L9GND")
		(20 "In9.Cu" signal "L10")
		(22 "In10.Cu" signal "L11GND")
		(24 "In11.Cu" signal "L12")
		(26 "In12.Cu" signal "L13GND")
		(2 "B.Cu" signal "BOTTOM")
		(9 "F.Adhes" user "F.Adhesive")
		(11 "B.Adhes" user "B.Adhesive")
		(13 "F.Paste" user "Package Geometry/Pastemask Top")
		(15 "B.Paste" user "Package Geometry/Pastemask Bottom")
		(5 "F.SilkS" user "Ref Des/Silkscreen Top")
		(7 "B.SilkS" user "Ref Des/Silkscreen Bottom")
		(1 "F.Mask" user "Board Geometry/Soldermask Top")
		(3 "B.Mask" user "Board Geometry/Soldermask Bottom")
		(17 "Dwgs.User" user "User.Drawings")
		(19 "Cmts.User" user "User.Comments")
		(21 "Eco1.User" user "User.Eco1")
		(23 "Eco2.User" user "User.Eco2")
		(25 "Edge.Cuts" user "Board Geometry/Outline")
		(27 "Margin" user)
		(31 "F.CrtYd" user "Package Geometry/Place Bound Top")
		(29 "B.CrtYd" user "Package Geometry/Place Bound Bottom")
		(35 "F.Fab" user "Ref Des/Assembly Top")
		(33 "B.Fab" user "Ref Des/Assembly Bottom")
	)
	(footprint ""
		(layer "F.Cu")
		(at 394.589 -88.2015)
		(property "Reference" "R2U9"
			(at 0 0 0)
			(layer "F.SilkS")
			(hide yes)
			(effects
				(font
					(size 1.27 1.27)
				)
			)
		)
		(property "Value" ""
			(at 0 0 0)
			(layer "F.Fab")
			(effects
				(font
					(size 1.27 1.27)
				)
			)
		)
		(duplicate_pad_numbers_are_jumpers no)
		(fp_poly
			(pts
				(xy -0.2794 -0.1016) (xy 0.2794 -0.1016) (xy 0.2794 0.9906) (xy -0.2794 0.9906)
			)
			(stroke
				(width 0)
				(type default)
			)
			(fill no)
			(layer "F.CrtYd")
		)
		(fp_line
			(start -0.2794 -0.1016)
			(end -0.2794 0.9906)
			(stroke
				(width 0.1)
				(type default)
			)
			(layer "F.Fab")
		)
		(fp_line
			(start -0.2794 0.9906)
			(end 0.2794 0.9906)
			(stroke
				(width 0.1)
				(type default)
			)
			(layer "F.Fab")
		)
		(fp_line
			(start 0.2794 -0.1016)
			(end -0.2794 -0.1016)
			(stroke
				(width 0.1)
				(type default)
			)
			(layer "F.Fab")
		)
		(fp_line
			(start 0.2794 0.9906)
			(end 0.2794 -0.1016)
			(stroke
				(width 0.1)
				(type default)
			)
			(layer "F.Fab")
		)
		(pad "1" smd rect
			(at 0 0)
			(size 0.508 0.508)
			(layers "F.Cu" "F.Mask" "F.Paste")
			(net "SMB_LAN_STBY_LVC3_SDA_R1")
		)
		(pad "2" smd rect
			(at 0 0.889)
			(size 0.508 0.508)
			(layers "F.Cu" "F.Mask" "F.Paste")
			(net "SMB_LAN_STBY_LVC3_SDA")
		)
		(zone
			(layer "F.Cu")
			(hatch none 0.5)
			(connect_pads
				(clearance 0)
			)
			(min_thickness 0.25)
			(keepout
				(tracks allowed)
				(vias not_allowed)
				(pads allowed)
				(copperpour not_allowed)
				(footprints allowed)
			)
			(placement
				(enabled no)
				(sheetname "")
			)
			(fill
				(thermal_gap 0.5)
				(thermal_bridge_width 0.5)
				(island_removal_mode 0)
			)
			(polygon
				(pts
					(xy 394.335 -87.9475) (xy 394.843 -87.9475) (xy 394.843 -87.5665) (xy 394.335 -87.5665)
				)
			)
		)
		(zone
			(layer "F.Cu")
			(hatch none 0.5)
			(connect_pads
				(clearance 0)
			)
			(min_thickness 0.25)
			(keepout
				(tracks not_allowed)
				(vias allowed)
				(pads allowed)
				(copperpour not_allowed)
				(footprints allowed)
			)
			(placement
				(enabled no)
				(sheetname "")
			)
			(fill
				(thermal_gap 0.5)
				(thermal_bridge_width 0.5)
				(island_removal_mode 0)
			)
			(polygon
				(pts
					(xy 394.335 -87.5665) (xy 394.843 -87.5665) (xy 394.843 -87.9475) (xy 394.335 -87.9475)
				)
			)
		)
	)
	(footprint ""
		(layer "F.Cu")
		(at 173.968664 -17.65681 90)
		(property "Reference" "C4F12"
			(at 0 0 90)
			(layer "F.SilkS")
			(hide yes)
			(effects
				(font
					(size 1.27 1.27)
				)
			)
		)
		(property "Value" ""
			(at 0 0 90)
			(layer "F.Fab")
			(effects
				(font
					(size 1.27 1.27)
				)
			)
		)
		(duplicate_pad_numbers_are_jumpers no)
		(fp_rect
			(start -0.3048 -0.1016)
			(end 0.3048 0.9906)
			(stroke
				(width 0)
				(type default)
			)
			(fill no)
			(layer "F.CrtYd")
		)
		(fp_line
			(start 0.3048 -0.1016)
			(end -0.3048 -0.1016)
			(stroke
				(width 0.1)
				(type default)
			)
			(layer "F.Fab")
		)
		(fp_line
			(start -0.3048 -0.1016)
			(end -0.3048 0.9906)
			(stroke
				(width 0.1)
				(type default)
			)
			(layer "F.Fab")
		)
		(fp_line
			(start 0.3048 0.9906)
			(end 0.3048 -0.1016)
			(stroke
				(width 0.1)
				(type default)
			)
			(layer "F.Fab")
		)
		(fp_line
			(start -0.3048 0.9906)
			(end 0.3048 0.9906)
			(stroke
				(width 0.1)
				(type default)
			)
			(layer "F.Fab")
		)
		(pad "1" smd rect
			(at 0 0 90)
			(size 0.508 0.508)
			(layers "F.Cu" "F.Mask" "F.Paste")
			(net "VR_PVPP_GHJ_PHASE")
		)
		(pad "2" smd rect
			(at 0 0.889 90)
			(size 0.508 0.508)
			(layers "F.Cu" "F.Mask" "F.Paste")
			(net "VR_PVPP_GHJ_SNUB")
		)
		(zone
			(layer "F.Cu")
			(hatch none 0.5)
			(connect_pads
				(clearance 0)
			)
			(min_thickness 0.25)
			(keepout
				(tracks not_allowed)
				(vias allowed)
				(pads allowed)
				(copperpour not_allowed)
				(footprints allowed)
			)
			(placement
				(enabled no)
				(sheetname "")
			)
			(fill
				(thermal_gap 0.5)
				(thermal_bridge_width 0.5)
				(island_removal_mode 0)
			)
			(polygon
				(pts
					(xy 174.222664 -17.40281) (xy 174.603664 -17.40281) (xy 174.603664 -17.91081) (xy 174.222664 -17.91081)
				)
			)
		)
		(zone
			(layer "F.Cu")
			(hatch none 0.5)
			(connect_pads
				(clearance 0)
			)
			(min_thickness 0.25)
			(keepout
				(tracks allowed)
				(vias not_allowed)
				(pads allowed)
				(copperpour not_allowed)
				(footprints allowed)
			)
			(placement
				(enabled no)
				(sheetname "")
			)
			(fill
				(thermal_gap 0.5)
				(thermal_bridge_width 0.5)
				(island_removal_mode 0)
			)
			(polygon
				(pts
					(xy 174.222664 -17.40281) (xy 174.603664 -17.40281) (xy 174.603664 -17.91081) (xy 174.222664 -17.91081)
				)
			)
		)
	)
	(footprint ""
		(layer "F.Cu")
		(at 412.4452 -111.633 90)
		(property "Reference" "R8B31"
			(at 0 0 90)
			(layer "F.SilkS")
			(hide yes)
			(effects
				(font
					(size 1.27 1.27)
				)
			)
		)
		(property "Value" ""
			(at 0 0 90)
			(layer "F.Fab")
			(effects
				(font
					(size 1.27 1.27)
				)
			)
		)
		(duplicate_pad_numbers_are_jumpers no)
		(fp_poly
			(pts
				(xy -0.2794 -0.1016) (xy 0.2794 -0.1016) (xy 0.2794 0.9906) (xy -0.2794 0.9906)
			)
			(stroke
				(width 0)
				(type default)
			)
			(fill no)
			(layer "F.CrtYd")
		)
		(fp_line
			(start 0.2794 -0.1016)
			(end -0.2794 -0.1016)
			(stroke
				(width 0.1)
				(type default)
			)
			(layer "F.Fab")
		)
		(fp_line
			(start -0.2794 -0.1016)
			(end -0.2794 0.9906)
			(stroke
				(width 0.1)
				(type default)
			)
			(layer "F.Fab")
		)
		(fp_line
			(start 0.2794 0.9906)
			(end 0.2794 -0.1016)
			(stroke
				(width 0.1)
				(type default)
			)
			(layer "F.Fab")
		)
		(fp_line
			(start -0.2794 0.9906)
			(end 0.2794 0.9906)
			(stroke
				(width 0.1)
				(type default)
			)
			(layer "F.Fab")
		)
		(pad "1" smd rect
			(at 0 0 90)
			(size 0.508 0.508)
			(layers "F.Cu" "F.Mask" "F.Paste")
			(net "P3V3_STBY")
		)
		(pad "2" smd rect
			(at 0 0.889 90)
			(size 0.508 0.508)
			(layers "F.Cu" "F.Mask" "F.Paste")
			(net "FM_THROTTLE_N")
		)
		(zone
			(layer "F.Cu")
			(hatch none 0.5)
			(connect_pads
				(clearance 0)
			)
			(min_thickness 0.25)
			(keepout
				(tracks allowed)
				(vias not_allowed)
				(pads allowed)
				(copperpour not_allowed)
				(footprints allowed)
			)
			(placement
				(enabled no)
				(sheetname "")
			)
			(fill
				(thermal_gap 0.5)
				(thermal_bridge_width 0.5)
				(island_removal_mode 0)
			)
			(polygon
				(pts
					(xy 412.6992 -111.379) (xy 412.6992 -111.887) (xy 413.0802 -111.887) (xy 413.0802 -111.379)
				)
			)
		)
		(zone
			(layer "F.Cu")
			(hatch none 0.5)
			(connect_pads
				(clearance 0)
			)
			(min_thickness 0.25)
			(keepout
				(tracks not_allowed)
				(vias allowed)
				(pads allowed)
				(copperpour not_allowed)
				(footprints allowed)
			)
			(placement
				(enabled no)
				(sheetname "")
			)
			(fill
				(thermal_gap 0.5)
				(thermal_bridge_width 0.5)
				(island_removal_mode 0)
			)
			(polygon
				(pts
					(xy 413.0802 -111.379) (xy 413.0802 -111.887) (xy 412.6992 -111.887) (xy 412.6992 -111.379)
				)
			)
		)
	)
)
